# T6G (Grand Teton) — schematic netlist excerpt (pin names and nets, part order shuffled) for the footprints in the layout excerpt that follows; sources: Cadence DE-HDL packaged netlist, KiCad conversion of 04192023_DAF0TMB3IC0_F0TG_MB_C_brd_V02_OCP.brd

C236  Q_CAP  2.7PF 50V 0.1PF NPO  pkg C0402  page 55 : A = XTAL_CPU1_X48M_X1 ; B = GND
C293  Q_CAP  1UF 4V 20% X6S  pkg 0201  page 334 : A = P0V9_CPU1_RT1_2A ; B = GND
C2178  Q_CAP  22UF 4V 20% X6S  pkg C0402  page 69 : A = PVDDCR_CPU0_P0 ; B = GND

(kicad_pcb
	(version 20260206)
	(generator "pcbnew")
	(generator_version "10.0")
	(general
		(thickness 1.6)
		(legacy_teardrops no)
	)
	(paper "A4")
	(title_block
		(title "04192023_DAF0TMB3IC0_F0TG_MB_C_brd_V02_OCP.brd")
		(comment 1 "Grand Teton / footprints 5033-5035 of 8354")
	)
	(layers
		(0 "F.Cu" signal "TOP")
		(4 "In1.Cu" signal "GND")
		(6 "In2.Cu" signal "IN1")
		(8 "In3.Cu" signal "GND1")
		(10 "In4.Cu" signal "IN2")
		(12 "In5.Cu" signal "GND2")
		(14 "In6.Cu" signal "IN3")
		(16 "In7.Cu" signal "GND3")
		(18 "In8.Cu" signal "VCC")
		(20 "In9.Cu" signal "VCC1")
		(22 "In10.Cu" signal "GND4")
		(24 "In11.Cu" signal "IN4")
		(26 "In12.Cu" signal "GND5")
		(28 "In13.Cu" signal "IN5")
		(30 "In14.Cu" signal "GND6")
		(32 "In15.Cu" signal "IN6")
		(34 "In16.Cu" signal "GND7")
		(2 "B.Cu" signal "BOTTOM")
		(9 "F.Adhes" user "F.Adhesive")
		(11 "B.Adhes" user "B.Adhesive")
		(13 "F.Paste" user "Package Geometry/Pastemask Top")
		(15 "B.Paste" user "Package Geometry/Pastemask Bottom")
		(5 "F.SilkS" user "Ref Des/Silkscreen Top")
		(7 "B.SilkS" user "Ref Des/Silkscreen Bottom")
		(1 "F.Mask" user "Board Geometry/Soldermask Top")
		(3 "B.Mask" user "Board Geometry/Soldermask Bottom")
		(17 "Dwgs.User" user "User.Drawings")
		(19 "Cmts.User" user "User.Comments")
		(21 "Eco1.User" user "User.Eco1")
		(23 "Eco2.User" user "User.Eco2")
		(25 "Edge.Cuts" user "Board Geometry/Outline")
		(27 "Margin" user)
		(31 "F.CrtYd" user "Package Geometry/Place Bound Top")
		(29 "B.CrtYd" user "Package Geometry/Place Bound Bottom")
		(35 "F.Fab" user "Ref Des/Assembly Top")
		(33 "B.Fab" user "Ref Des/Assembly Bottom")
	)
	(footprint ""
		(layer "B.Cu")
		(at 353.136454 -248.47931)
		(property "Reference" "C2178"
			(at 0 0 0)
			(layer "B.SilkS")
			(hide yes)
			(effects
				(font
					(size 1.27 1.27)
				)
				(justify mirror)
			)
		)
		(property "Value" ""
			(at 0 0 0)
			(layer "B.Fab")
			(effects
				(font
					(size 1.27 1.27)
				)
				(justify mirror)
			)
		)
		(duplicate_pad_numbers_are_jumpers no)
		(fp_line
			(start -0.7874 -0.4064)
			(end -0.7874 0.4064)
			(stroke
				(width 0.1524)
				(type default)
			)
			(layer "B.SilkS")
		)
		(fp_line
			(start -0.7874 0.4064)
			(end 0.7874 0.4064)
			(stroke
				(width 0.1524)
				(type default)
			)
			(layer "B.SilkS")
		)
		(fp_line
			(start 0.7874 -0.4064)
			(end -0.7874 -0.4064)
			(stroke
				(width 0.1524)
				(type default)
			)
			(layer "B.SilkS")
		)
		(fp_line
			(start 0.7874 0.4064)
			(end 0.7874 -0.4064)
			(stroke
				(width 0.1524)
				(type default)
			)
			(layer "B.SilkS")
		)
		(fp_line
			(start -0.67945 -0.3048)
			(end -0.67945 0.3048)
			(stroke
				(width 0.1)
				(type default)
			)
			(layer "B.Fab")
		)
		(fp_line
			(start -0.67945 0.3048)
			(end -0.120396 0.3048)
			(stroke
				(width 0.1)
				(type default)
			)
			(layer "B.Fab")
		)
		(fp_line
			(start -0.12065 -0.3048)
			(end -0.67945 -0.3048)
			(stroke
				(width 0.1)
				(type default)
			)
			(layer "B.Fab")
		)
		(fp_line
			(start -0.12065 -0.2794)
			(end -0.12065 -0.3048)
			(stroke
				(width 0.1)
				(type default)
			)
			(layer "B.Fab")
		)
		(fp_line
			(start -0.120396 0.2794)
			(end 0.12065 0.2794)
			(stroke
				(width 0.1)
				(type default)
			)
			(layer "B.Fab")
		)
		(fp_line
			(start -0.120396 0.3048)
			(end -0.120396 0.2794)
			(stroke
				(width 0.1)
				(type default)
			)
			(layer "B.Fab")
		)
		(fp_line
			(start 0.12065 -0.305054)
			(end 0.12065 -0.2794)
			(stroke
				(width 0.1)
				(type default)
			)
			(layer "B.Fab")
		)
		(fp_line
			(start 0.12065 -0.2794)
			(end -0.12065 -0.2794)
			(stroke
				(width 0.1)
				(type default)
			)
			(layer "B.Fab")
		)
		(fp_line
			(start 0.12065 0.2794)
			(end 0.12065 0.3048)
			(stroke
				(width 0.1)
				(type default)
			)
			(layer "B.Fab")
		)
		(fp_line
			(start 0.12065 0.3048)
			(end 0.67945 0.3048)
			(stroke
				(width 0.1)
				(type default)
			)
			(layer "B.Fab")
		)
		(fp_line
			(start 0.67945 -0.305054)
			(end 0.12065 -0.305054)
			(stroke
				(width 0.1)
				(type default)
			)
			(layer "B.Fab")
		)
		(fp_line
			(start 0.67945 0.3048)
			(end 0.67945 -0.305054)
			(stroke
				(width 0.1)
				(type default)
			)
			(layer "B.Fab")
		)
		(pad "1" smd circle
			(at 0.40005 0 180)
			(size 0 0)
			(layers "B.Cu" "B.Mask" "B.Paste")
			(net "PVDDCR_CPU0_P0")
		)
		(pad "2" smd circle
			(at -0.40005 0 180)
			(size 0 0)
			(layers "B.Cu" "B.Mask" "B.Paste")
			(net "GND")
		)
	)
	(footprint ""
		(layer "B.Cu")
		(at 79.700628 -385.50088 -90)
		(property "Reference" "C293"
			(at 0 0 90)
			(layer "B.SilkS")
			(hide yes)
			(effects
				(font
					(size 1.27 1.27)
				)
				(justify mirror)
			)
		)
		(property "Value" ""
			(at 0 0 90)
			(layer "B.Fab")
			(effects
				(font
					(size 1.27 1.27)
				)
				(justify mirror)
			)
		)
		(duplicate_pad_numbers_are_jumpers no)
		(fp_line
			(start -0.299974 0.150114)
			(end 0.299974 0.150114)
			(stroke
				(width 0.1)
				(type default)
			)
			(layer "B.Fab")
		)
		(fp_line
			(start 0.299974 0.150114)
			(end 0.299974 -0.150114)
			(stroke
				(width 0.1)
				(type default)
			)
			(layer "B.Fab")
		)
		(fp_line
			(start -0.299974 -0.150114)
			(end -0.299974 0.150114)
			(stroke
				(width 0.1)
				(type default)
			)
			(layer "B.Fab")
		)
		(fp_line
			(start 0.299974 -0.150114)
			(end -0.299974 -0.150114)
			(stroke
				(width 0.1)
				(type default)
			)
			(layer "B.Fab")
		)
		(pad "1" smd rect
			(at 0.2667 0 90)
			(size 0.3048 0.381)
			(layers "B.Cu" "B.Mask" "B.Paste")
			(net "P0V9_CPU1_RT1_2A")
		)
		(pad "2" smd rect
			(at -0.2667 0 90)
			(size 0.3048 0.381)
			(layers "B.Cu" "B.Mask" "B.Paste")
			(net "GND")
		)
	)
	(footprint ""
		(layer "B.Cu")
		(at 148.122386 -314.47105)
		(property "Reference" "C236"
			(at 0 0 0)
			(layer "B.SilkS")
			(hide yes)
			(effects
				(font
					(size 1.27 1.27)
				)
				(justify mirror)
			)
		)
		(property "Value" ""
			(at 0 0 0)
			(layer "B.Fab")
			(effects
				(font
					(size 1.27 1.27)
				)
				(justify mirror)
			)
		)
		(duplicate_pad_numbers_are_jumpers no)
		(fp_line
			(start -0.7874 -0.4064)
			(end -0.7874 0.4064)
			(stroke
				(width 0.1524)
				(type default)
			)
			(layer "B.SilkS")
		)
		(fp_line
			(start -0.7874 0.4064)
			(end 0.7874 0.4064)
			(stroke
				(width 0.1524)
				(type default)
			)
			(layer "B.SilkS")
		)
		(fp_line
			(start 0.7874 -0.4064)
			(end -0.7874 -0.4064)
			(stroke
				(width 0.1524)
				(type default)
			)
			(layer "B.SilkS")
		)
		(fp_line
			(start 0.7874 0.4064)
			(end 0.7874 -0.4064)
			(stroke
				(width 0.1524)
				(type default)
			)
			(layer "B.SilkS")
		)
		(fp_line
			(start -0.67945 -0.3048)
			(end -0.67945 0.3048)
			(stroke
				(width 0.1)
				(type default)
			)
			(layer "B.Fab")
		)
		(fp_line
			(start -0.67945 0.3048)
			(end -0.120396 0.3048)
			(stroke
				(width 0.1)
				(type default)
			)
			(layer "B.Fab")
		)
		(fp_line
			(start -0.12065 -0.3048)
			(end -0.67945 -0.3048)
			(stroke
				(width 0.1)
				(type default)
			)
			(layer "B.Fab")
		)
		(fp_line
			(start -0.12065 -0.2794)
			(end -0.12065 -0.3048)
			(stroke
				(width 0.1)
				(type default)
			)
			(layer "B.Fab")
		)
		(fp_line
			(start -0.120396 0.2794)
			(end 0.12065 0.2794)
			(stroke
				(width 0.1)
				(type default)
			)
			(layer "B.Fab")
		)
		(fp_line
			(start -0.120396 0.3048)
			(end -0.120396 0.2794)
			(stroke
				(width 0.1)
				(type default)
			)
			(layer "B.Fab")
		)
		(fp_line
			(start 0.12065 -0.305054)
			(end 0.12065 -0.2794)
			(stroke
				(width 0.1)
				(type default)
			)
			(layer "B.Fab")
		)
		(fp_line
			(start 0.12065 -0.2794)
			(end -0.12065 -0.2794)
			(stroke
				(width 0.1)
				(type default)
			)
			(layer "B.Fab")
		)
		(fp_line
			(start 0.12065 0.2794)
			(end 0.12065 0.3048)
			(stroke
				(width 0.1)
				(type default)
			)
			(layer "B.Fab")
		)
		(fp_line
			(start 0.12065 0.3048)
			(end 0.67945 0.3048)
			(stroke
				(width 0.1)
				(type default)
			)
			(layer "B.Fab")
		)
		(fp_line
			(start 0.67945 -0.305054)
			(end 0.12065 -0.305054)
			(stroke
				(width 0.1)
				(type default)
			)
			(layer "B.Fab")
		)
		(fp_line
			(start 0.67945 0.3048)
			(end 0.67945 -0.305054)
			(stroke
				(width 0.1)
				(type default)
			)
			(layer "B.Fab")
		)
		(pad "1" smd circle
			(at 0.40005 0 180)
			(size 0 0)
			(layers "B.Cu" "B.Mask" "B.Paste")
			(net "XTAL_CPU1_X48M_X1")
		)
		(pad "2" smd circle
			(at -0.40005 0 180)
			(size 0 0)
			(layers "B.Cu" "B.Mask" "B.Paste")
			(net "GND")
		)
	)
)
